# S9S_MB_2U (Grand Teton) — schematic netlist excerpt (pin names and nets, part order shuffled) for the footprints in the layout excerpt that follows; sources: Cadence DE-HDL packaged netlist, KiCad conversion of 03242023_DA0F0TMBIJ0_F0T_Motherboard_J_brd_V01_OCP.brd

J1  SCONN288_ADR50017P130CC  SCONN288_ADR50017-P130CC IO  pkg DDR288S_1-1VXB  page 82
  VIN_BULK0  = P12V_S3_AUX_CPU0_NVDIMM
  RFU0  = TP_CHA_CPU0_DIMM1_FRU_0
  VIN_MGMT  = P3V3_AUX
  HSCL  = I3C_SPD_DDRABCD_CPU0_LVC1_SCL_R
  HSDA  = I3C_SPD_DDRABCD_CPU0_LVC1_SDA
  VSS0  = GND
  DQ0_A  = M_A_CPU0_SA_DQ<0>
  VSS1  = GND
  DQ1_A  = M_A_CPU0_SA_DQ<1>
  VSS2  = GND
  DQS0_A_T  = M_A_CPU0_SA_DQS_DP<0>
  DQS0_A_C  = M_A_CPU0_SA_DQS_DN<0>
  VSS3  = GND
  DQ4_A  = M_A_CPU0_SA_DQ<4>
  VSS4  = GND
  DQ5_A  = M_A_CPU0_SA_DQ<5>
  VSS5  = GND
  DQ8_A  = M_A_CPU0_SA_DQ<8>
  VSS6  = GND
  DQ9_A  = M_A_CPU0_SA_DQ<9>
  VSS7  = GND
  DQS1_A_T  = M_A_CPU0_SA_DQS_DP<1>
  DQS1_A_C  = M_A_CPU0_SA_DQS_DN<1>
  VSS8  = GND
  DQ12_A  = M_A_CPU0_SA_DQ<12>
  VSS9  = GND
  DQ13_A  = M_A_CPU0_SA_DQ<13>
  VSS10  = GND
  DQ16_A  = M_A_CPU0_SA_DQ<16>
  VSS11  = GND
  DQ17_A  = M_A_CPU0_SA_DQ<17>
  VSS12  = GND
  DQS2_A_T  = M_A_CPU0_SA_DQS_DP<2>
  DQS2_A_C  = M_A_CPU0_SA_DQS_DN<2>
  VSS13  = GND
  DQ20_A  = M_A_CPU0_SA_DQ<20>
  VSS14  = GND
  DQ21_A  = M_A_CPU0_SA_DQ<21>
  VSS15  = GND
  DQ24_A  = M_A_CPU0_SA_DQ<24>
  VSS16  = GND
  DQ25_A  = M_A_CPU0_SA_DQ<25>
  VSS17  = GND
  DQS3_A_T  = M_A_CPU0_SA_DQS_DP<3>
  DQS3_A_C  = M_A_CPU0_SA_DQS_DN<3>
  VSS18  = GND
  DQ28_A  = M_A_CPU0_SA_DQ<28>
  VSS19  = GND
  DQ29_A  = M_A_CPU0_SA_DQ<29>
  VSS20  = GND
  CB0_A  = M_A_CPU0_SA_CB<0>
  VSS21  = GND
  CB1_A  = M_A_CPU0_SA_CB<1>
  VSS22  = GND
  DQS4_A_T  = M_A_CPU0_SA_DQS_DP<4>
  DQS4_A_C  = M_A_CPU0_SA_DQS_DN<4>
  VSS23  = GND
  CB4_A  = M_A_CPU0_SA_CB<4>
  VSS24  = GND
  CB5_A  = M_A_CPU0_SA_CB<5>
  VSS25  = GND
  ALERT_N  = M_A_CPU0_ALERT_N
  VSS26  = GND
  CS0_A_N  = M_A_CPU0_SA_CS_N<0>
  VSS27  = GND
  CA0_A  = M_A_CPU0_SA_CA<0>
  VSS28  = GND
  CA2_A  = M_A_CPU0_SA_CA<2>
  VSS29  = GND
  CA4_A  = M_A_CPU0_SA_CA<4>
  VSS30  = GND
  CA6_A  = M_A_CPU0_SA_CA<6>
  VSS31  = GND
  PAR_A  = M_A_CPU0_SA_PAR
  VSS32  = GND
  CA0_B  = M_A_CPU0_SB_CA<0>
  VSS33  = GND
  CA2_B  = M_A_CPU0_SB_CA<2>
  VSS34  = GND
  CA4_B  = M_A_CPU0_SB_CA<4>
  VSS35  = GND
  CA6_B  = M_A_CPU0_SB_CA<6>
  VSS36  = GND
  CS0_B_N  = M_A_CPU0_SB_CS_N<0>
  VSS37  = GND
  \lbd||rsp_a_n\  = M_A_CPU0_SA_RSP<0>
  \lbs||rsp_b_n\  = M_A_CPU0_SB_RSP<0>
  VSS38  = GND
  CB4_B  = M_A_CPU0_SB_CB<4>
  VSS39  = GND
  CB5_B  = M_A_CPU0_SB_CB<5>
  VSS40  = GND
  \dqs9_b_t||tdqs9_b_t||dbi4_b_n\  = M_A_CPU0_SB_DQS_DP<9>
  \dqs9_b_c||tdqs9_b_c\  = M_A_CPU0_SB_DQS_DN<9>
  VSS41  = GND
  CB0_B  = M_A_CPU0_SB_CB<0>
  VSS42  = GND
  CB1_B  = M_A_CPU0_SB_CB<1>
  VSS43  = GND
  DQ0_B  = M_A_CPU0_SB_DQ<0>
  VSS44  = GND
  DQ1_B  = M_A_CPU0_SB_DQ<1>
  VSS45  = GND
  DQS0_B_T  = M_A_CPU0_SB_DQS_DP<0>
  DQS0_B_C  = M_A_CPU0_SB_DQS_DN<0>
  VSS46  = GND
  DQ4_B  = M_A_CPU0_SB_DQ<4>
  VSS47  = GND
  DQ5_B  = M_A_CPU0_SB_DQ<5>
  VSS48  = GND
  DQ8_B  = M_A_CPU0_SB_DQ<8>
  VSS49  = GND
  DQ9_B  = M_A_CPU0_SB_DQ<9>
  VSS50  = GND
  DQS1_B_T  = M_A_CPU0_SB_DQS_DP<1>
  DQS1_B_C  = M_A_CPU0_SB_DQS_DN<1>
  VSS51  = GND
  DQ12_B  = M_A_CPU0_SB_DQ<12>
  VSS52  = GND
  DQ13_B  = M_A_CPU0_SB_DQ<13>
  VSS53  = GND
  DQ16_B  = M_A_CPU0_SB_DQ<16>
  VSS54  = GND
  DQ17_B  = M_A_CPU0_SB_DQ<17>
  VSS55  = GND
  DQS2_B_T  = M_A_CPU0_SB_DQS_DP<2>
  DQS2_B_C  = M_A_CPU0_SB_DQS_DN<2>
  VSS56  = GND
  DQ20_B  = M_A_CPU0_SB_DQ<20>
  VSS57  = GND
  DQ21_B  = M_A_CPU0_SB_DQ<21>
  VSS58  = GND
  DQ24_B  = M_A_CPU0_SB_DQ<24>
  VSS59  = GND
  DQ25_B  = M_A_CPU0_SB_DQ<25>
  VSS60  = GND
  DQS3_B_T  = M_A_CPU0_SB_DQS_DP<3>
  DQS3_B_C  = M_A_CPU0_SB_DQS_DN<3>
  VSS61  = GND
  DQ28_B  = M_A_CPU0_SB_DQ<28>
  VSS62  = GND
  DQ29_B  = M_A_CPU0_SB_DQ<29>
  VSS63  = GND
  RFU1  = TP_CHA_CPU0_DIMM1_FRU_1
  VIN_BULK1  = P12V_S3_AUX_CPU0_NVDIMM
  VIN_BULK2  = P12V_S3_AUX_CPU0_NVDIMM
  \pwr_good||fail_n\  = PWRGD_CHA_CPU0_DIMM1
  HSA  = PD_CHA_CPU0_DIMM1_SAA
  RFU2  = TP_CHA_CPU0_DIMM1_FRU_2
  RFU3  = TP_CHA_CPU0_DIMM1_FRU_3
  VSS64  = GND
  DQ2_A  = M_A_CPU0_SA_DQ<2>
  VSS65  = GND
  DQ3_A  = M_A_CPU0_SA_DQ<3>
  VSS66  = GND
  \dqs5_a_c||tdqs5_a_c||dqs5_a_t||tdqs5_a_t\  = M_A_CPU0_SA_DQS_DN<5>
  \dqs5_a_t||tdqs5_a_t\  = M_A_CPU0_SA_DQS_DP<5>
  VSS67  = GND
  DQ6_A  = M_A_CPU0_SA_DQ<6>
  VSS68  = GND
  DQ7_A  = M_A_CPU0_SA_DQ<7>
  VSS69  = GND
  DQ10_A  = M_A_CPU0_SA_DQ<10>
  VSS70  = GND
  DQ11_A  = M_A_CPU0_SA_DQ<11>
  VSS71  = GND
  \dqs6_a_c||tdqs6_a_c||dqs6_a_t||tdqs6_a_t\  = M_A_CPU0_SA_DQS_DN<6>
  \dqs6_a_t||tdqs6_a_t\  = M_A_CPU0_SA_DQS_DP<6>
  VSS72  = GND
  DQ14_A  = M_A_CPU0_SA_DQ<14>
  VSS73  = GND
  DQ15_A  = M_A_CPU0_SA_DQ<15>
  VSS74  = GND
  DQ18_A  = M_A_CPU0_SA_DQ<18>
  VSS75  = GND
  DQ19_A  = M_A_CPU0_SA_DQ<19>
  VSS76  = GND
  \dqs7_a_c||tdqs7_a_c\  = M_A_CPU0_SA_DQS_DN<7>
  \dqs7_a_t||tdqs7_a_t\  = M_A_CPU0_SA_DQS_DP<7>
  VSS77  = GND
  DQ22_A  = M_A_CPU0_SA_DQ<22>
  VSS78  = GND
  DQ23_A  = M_A_CPU0_SA_DQ<23>
  VSS79  = GND
  DQ26_A  = M_A_CPU0_SA_DQ<26>
  VSS80  = GND
  DQ27_A  = M_A_CPU0_SA_DQ<27>
  VSS81  = GND
  \dqs8_a_c||tdqs8_a_c\  = M_A_CPU0_SA_DQS_DN<8>
  \dqs8_a_t||tdqs8_a_t\  = M_A_CPU0_SA_DQS_DP<8>
  VSS82  = GND
  DQ30_A  = M_A_CPU0_SA_DQ<30>
  VSS83  = GND
  DQ31_A  = M_A_CPU0_SA_DQ<31>
  VSS84  = GND
  CB2_A  = M_A_CPU0_SA_CB<2>
  VSS85  = GND
  CB3_A  = M_A_CPU0_SA_CB<3>
  VSS86  = GND
  \dqs9_a_c||tdqs9_a_c\  = M_A_CPU0_SA_DQS_DN<9>
  \dqs9_a_t||tdqs9_a_t\  = M_A_CPU0_SA_DQS_DP<9>
  VSS87  = GND
  CB6_A  = M_A_CPU0_SA_CB<6>
  VSS88  = GND
  CB7_A  = M_A_CPU0_SA_CB<7>
  VSS89  = GND
  RESET_N  = RST_M_AB_CPU0_FPGA_N
  VSS90  = GND
  CS1_A_N  = M_A_CPU0_SA_CS_N<1>
  VSS91  = GND
  CA1_A  = M_A_CPU0_SA_CA<1>
  VSS92  = GND
  CA3_A  = M_A_CPU0_SA_CA<3>
  VSS93  = GND
  CA5_A  = M_A_CPU0_SA_CA<5>
  VSS94  = GND
  CK_T  = M_A_CPU0_CLK_DP<0>
  CK_C  = M_A_CPU0_CLK_DN<0>
  VSS95  = GND
  RFU4  = TP_CHA_CPU0_DIMM1_FRU_4
  CA1_B  = M_A_CPU0_SB_CA<1>
  VSS96  = GND
  CA3_B  = M_A_CPU0_SB_CA<3>
  VSS97  = GND
  CA5_B  = M_A_CPU0_SB_CA<5>
  VSS98  = GND
  PAR_B  = M_A_CPU0_SB_PAR
  VSS99  = GND
  CS1_B_N  = M_A_CPU0_SB_CS_N<1>
  VSS100  = GND
  RFU5  = TP_CHA_CPU0_DIMM1_FRU_5
  RFU6  = TP_CHA_CPU0_DIMM1_FRU_6
  VSS101  = GND
  CB6_B  = M_A_CPU0_SB_CB<6>
  VSS102  = GND
  CB7_B  = M_A_CPU0_SB_CB<7>
  VSS103  = GND
  DQS4_B_C  = M_A_CPU0_SB_DQS_DN<4>
  DQS4_B_T  = M_A_CPU0_SB_DQS_DP<4>
  VSS104  = GND
  CB2_B  = M_A_CPU0_SB_CB<2>
  VSS105  = GND
  CB3_B  = M_A_CPU0_SB_CB<3>
  VSS106  = GND
  DQ2_B  = M_A_CPU0_SB_DQ<2>
  VSS107  = GND
  DQ3_B  = M_A_CPU0_SB_DQ<3>
  VSS108  = GND
  \dqs5_b_c||tdqs5_b_c\  = M_A_CPU0_SB_DQS_DN<5>
  \dqs5_b_t||tdqs5_b_t\  = M_A_CPU0_SB_DQS_DP<5>
  VSS109  = GND
  DQ6_B  = M_A_CPU0_SB_DQ<6>
  VSS110  = GND
  DQ7_B  = M_A_CPU0_SB_DQ<7>
  VSS111  = GND
  DQ10_B  = M_A_CPU0_SB_DQ<10>
  VSS112  = GND
  DQ11_B  = M_A_CPU0_SB_DQ<11>
  VSS113  = GND
  \dqs6_b_c||tdqs6_b_c\  = M_A_CPU0_SB_DQS_DN<6>
  \dqs6_b_t||tdqs6_b_t\  = M_A_CPU0_SB_DQS_DP<6>
  VSS114  = GND
  DQ14_B  = M_A_CPU0_SB_DQ<14>
  VSS115  = GND
  DQ15_B  = M_A_CPU0_SB_DQ<15>
  VSS116  = GND
  DQ18_B  = M_A_CPU0_SB_DQ<18>
  VSS117  = GND
  DQ19_B  = M_A_CPU0_SB_DQ<19>
  VSS118  = GND
  \dqs7_b_c||tdqs7_b_c\  = M_A_CPU0_SB_DQS_DN<7>
  \dqs7_b_t||tdqs7_b_t\  = M_A_CPU0_SB_DQS_DP<7>
  VSS119  = GND
  DQ22_B  = M_A_CPU0_SB_DQ<22>
  VSS120  = GND
  DQ23_B  = M_A_CPU0_SB_DQ<23>
  VSS121  = GND
  DQ26_B  = M_A_CPU0_SB_DQ<26>
  VSS122  = GND
  DQ27_B  = M_A_CPU0_SB_DQ<27>
  VSS123  = GND
  \dqs8_b_c||tdqs8_b_c\  = M_A_CPU0_SB_DQS_DN<8>
  \dqs8_b_t||tdqs8_b_t\  = M_A_CPU0_SB_DQS_DP<8>
  VSS124  = GND
  DQ30_B  = M_A_CPU0_SB_DQ<30>
  VSS125  = GND
  DQ31_B  = M_A_CPU0_SB_DQ<31>
  VSS126  = GND
  G1  = GND
  G2  = GND
  G3  = GND

(kicad_pcb
	(version 20260206)
	(generator "pcbnew")
	(generator_version "10.0")
	(general
		(thickness 1.6)
		(legacy_teardrops no)
	)
	(paper "A4")
	(title_block
		(title "03242023_DA0F0TMBIJ0_F0T_Motherboard_J_brd_V01_OCP.brd")
		(comment 1 "Grand Teton / footprint 1236 of 6105 (J1), pads 1-45 of 291")
	)
	(layers
		(0 "F.Cu" signal "TOP")
		(4 "In1.Cu" signal "GND")
		(6 "In2.Cu" signal "IN1")
		(8 "In3.Cu" signal "GND1")
		(10 "In4.Cu" signal "IN2")
		(12 "In5.Cu" signal "GND2")
		(14 "In6.Cu" signal "IN3")
		(16 "In7.Cu" signal "GND3")
		(18 "In8.Cu" signal "VCC")
		(20 "In9.Cu" signal "VCC1")
		(22 "In10.Cu" signal "GND4")
		(24 "In11.Cu" signal "IN4")
		(26 "In12.Cu" signal "GND5")
		(28 "In13.Cu" signal "IN5")
		(30 "In14.Cu" signal "GND6")
		(32 "In15.Cu" signal "IN6")
		(34 "In16.Cu" signal "GND7")
		(2 "B.Cu" signal "BOTTOM")
		(9 "F.Adhes" user "F.Adhesive")
		(11 "B.Adhes" user "B.Adhesive")
		(13 "F.Paste" user "Package Geometry/Pastemask Top")
		(15 "B.Paste" user "Package Geometry/Pastemask Bottom")
		(5 "F.SilkS" user "Ref Des/Silkscreen Top")
		(7 "B.SilkS" user "Ref Des/Silkscreen Bottom")
		(1 "F.Mask" user "Board Geometry/Soldermask Top")
		(3 "B.Mask" user "Board Geometry/Soldermask Bottom")
		(17 "Dwgs.User" user "User.Drawings")
		(19 "Cmts.User" user "User.Comments")
		(21 "Eco1.User" user "User.Eco1")
		(23 "Eco2.User" user "User.Eco2")
		(25 "Edge.Cuts" user "Board Geometry/Outline")
		(27 "Margin" user)
		(31 "F.CrtYd" user "Package Geometry/Place Bound Top")
		(29 "B.CrtYd" user "Package Geometry/Place Bound Bottom")
		(35 "F.Fab" user "Ref Des/Assembly Top")
		(33 "B.Fab" user "Ref Des/Assembly Bottom")
	)
	(footprint ""
		(layer "F.Cu")
		(at 303.393348 -258.091686)
		(property "Reference" "J1"
			(at -3.683 -81.702148 0)
			(unlocked yes)
			(layer "F.SilkS")
			(effects
				(font
					(size 0.7874 0.5842)
					(thickness 0.1524)
				)
				(justify left)
			)
		)
		(property "Value" ""
			(at 0 0 0)
			(layer "F.Fab")
			(effects
				(font
					(size 1.27 1.27)
				)
			)
		)
		(duplicate_pad_numbers_are_jumpers no)
		(pad "1" smd rect
			(at -2.050034 -63.324994 270)
			(size 0.519938 1.4986)
			(layers "F.Cu" "F.Mask" "F.Paste")
			(net "P12V_S3_AUX_CPU0_NVDIMM")
		)
		(pad "2" smd rect
			(at -2.050034 -62.47511 270)
			(size 0.519938 1.4986)
			(layers "F.Cu" "F.Mask" "F.Paste")
			(net "TP_CHA_CPU0_DIMM1_FRU_0")
		)
		(pad "3" smd rect
			(at -2.050034 -61.624972 270)
			(size 0.519938 1.4986)
			(layers "F.Cu" "F.Mask" "F.Paste")
			(net "P3V3_AUX")
		)
		(pad "4" smd rect
			(at -2.050034 -60.775088 270)
			(size 0.519938 1.4986)
			(layers "F.Cu" "F.Mask" "F.Paste")
			(net "I3C_SPD_DDRABCD_CPU0_LVC1_SCL_R")
		)
		(pad "5" smd rect
			(at -2.050034 -59.92495 270)
			(size 0.519938 1.4986)
			(layers "F.Cu" "F.Mask" "F.Paste")
			(net "I3C_SPD_DDRABCD_CPU0_LVC1_SDA")
		)
		(pad "6" smd rect
			(at -2.050034 -59.075066 270)
			(size 0.519938 1.4986)
			(layers "F.Cu" "F.Mask" "F.Paste")
			(net "GND")
		)
		(pad "7" smd rect
			(at -2.050034 -58.224928 270)
			(size 0.519938 1.4986)
			(layers "F.Cu" "F.Mask" "F.Paste")
			(net "M_A_CPU0_SA_DQ<0>")
		)
		(pad "8" smd rect
			(at -2.050034 -57.375044 270)
			(size 0.519938 1.4986)
			(layers "F.Cu" "F.Mask" "F.Paste")
			(net "GND")
		)
		(pad "9" smd rect
			(at -2.050034 -56.524906 270)
			(size 0.519938 1.4986)
			(layers "F.Cu" "F.Mask" "F.Paste")
			(net "M_A_CPU0_SA_DQ<1>")
		)
		(pad "10" smd rect
			(at -2.050034 -55.675022 270)
			(size 0.519938 1.4986)
			(layers "F.Cu" "F.Mask" "F.Paste")
			(net "GND")
		)
		(pad "11" smd rect
			(at -2.050034 -54.824884 270)
			(size 0.519938 1.4986)
			(layers "F.Cu" "F.Mask" "F.Paste")
			(net "M_A_CPU0_SA_DQS_DP<0>")
		)
		(pad "12" smd rect
			(at -2.050034 -53.975 270)
			(size 0.519938 1.4986)
			(layers "F.Cu" "F.Mask" "F.Paste")
			(net "M_A_CPU0_SA_DQS_DN<0>")
		)
		(pad "13" smd rect
			(at -2.050034 -53.125116 270)
			(size 0.519938 1.4986)
			(layers "F.Cu" "F.Mask" "F.Paste")
			(net "GND")
		)
		(pad "14" smd rect
			(at -2.050034 -52.274978 270)
			(size 0.519938 1.4986)
			(layers "F.Cu" "F.Mask" "F.Paste")
			(net "M_A_CPU0_SA_DQ<4>")
		)
		(pad "15" smd rect
			(at -2.050034 -51.425094 270)
			(size 0.519938 1.4986)
			(layers "F.Cu" "F.Mask" "F.Paste")
			(net "GND")
		)
		(pad "16" smd rect
			(at -2.050034 -50.574956 270)
			(size 0.519938 1.4986)
			(layers "F.Cu" "F.Mask" "F.Paste")
			(net "M_A_CPU0_SA_DQ<5>")
		)
		(pad "17" smd rect
			(at -2.050034 -49.725072 270)
			(size 0.519938 1.4986)
			(layers "F.Cu" "F.Mask" "F.Paste")
			(net "GND")
		)
		(pad "18" smd rect
			(at -2.050034 -48.874934 270)
			(size 0.519938 1.4986)
			(layers "F.Cu" "F.Mask" "F.Paste")
			(net "M_A_CPU0_SA_DQ<8>")
		)
		(pad "19" smd rect
			(at -2.050034 -48.02505 270)
			(size 0.519938 1.4986)
			(layers "F.Cu" "F.Mask" "F.Paste")
			(net "GND")
		)
		(pad "20" smd rect
			(at -2.050034 -47.174912 270)
			(size 0.519938 1.4986)
			(layers "F.Cu" "F.Mask" "F.Paste")
			(net "M_A_CPU0_SA_DQ<9>")
		)
		(pad "21" smd rect
			(at -2.050034 -46.325028 270)
			(size 0.519938 1.4986)
			(layers "F.Cu" "F.Mask" "F.Paste")
			(net "GND")
		)
		(pad "22" smd rect
			(at -2.050034 -45.47489 270)
			(size 0.519938 1.4986)
			(layers "F.Cu" "F.Mask" "F.Paste")
			(net "M_A_CPU0_SA_DQS_DP<1>")
		)
		(pad "23" smd rect
			(at -2.050034 -44.625006 270)
			(size 0.519938 1.4986)
			(layers "F.Cu" "F.Mask" "F.Paste")
			(net "M_A_CPU0_SA_DQS_DN<1>")
		)
		(pad "24" smd rect
			(at -2.050034 -43.775122 270)
			(size 0.519938 1.4986)
			(layers "F.Cu" "F.Mask" "F.Paste")
			(net "GND")
		)
		(pad "25" smd rect
			(at -2.050034 -42.924984 270)
			(size 0.519938 1.4986)
			(layers "F.Cu" "F.Mask" "F.Paste")
			(net "M_A_CPU0_SA_DQ<12>")
		)
		(pad "26" smd rect
			(at -2.050034 -42.0751 270)
			(size 0.519938 1.4986)
			(layers "F.Cu" "F.Mask" "F.Paste")
			(net "GND")
		)
		(pad "27" smd rect
			(at -2.050034 -41.224962 270)
			(size 0.519938 1.4986)
			(layers "F.Cu" "F.Mask" "F.Paste")
			(net "M_A_CPU0_SA_DQ<13>")
		)
		(pad "28" smd rect
			(at -2.050034 -40.375078 270)
			(size 0.519938 1.4986)
			(layers "F.Cu" "F.Mask" "F.Paste")
			(net "GND")
		)
		(pad "29" smd rect
			(at -2.050034 -39.52494 270)
			(size 0.519938 1.4986)
			(layers "F.Cu" "F.Mask" "F.Paste")
			(net "M_A_CPU0_SA_DQ<16>")
		)
		(pad "30" smd rect
			(at -2.050034 -38.675056 270)
			(size 0.519938 1.4986)
			(layers "F.Cu" "F.Mask" "F.Paste")
			(net "GND")
		)
		(pad "31" smd rect
			(at -2.050034 -37.824918 270)
			(size 0.519938 1.4986)
			(layers "F.Cu" "F.Mask" "F.Paste")
			(net "M_A_CPU0_SA_DQ<17>")
		)
		(pad "32" smd rect
			(at -2.050034 -36.975034 270)
			(size 0.519938 1.4986)
			(layers "F.Cu" "F.Mask" "F.Paste")
			(net "GND")
		)
		(pad "33" smd rect
			(at -2.050034 -36.124896 270)
			(size 0.519938 1.4986)
			(layers "F.Cu" "F.Mask" "F.Paste")
			(net "M_A_CPU0_SA_DQS_DP<2>")
		)
		(pad "34" smd rect
			(at -2.050034 -35.275012 270)
			(size 0.519938 1.4986)
			(layers "F.Cu" "F.Mask" "F.Paste")
			(net "M_A_CPU0_SA_DQS_DN<2>")
		)
		(pad "35" smd rect
			(at -2.050034 -34.425128 270)
			(size 0.519938 1.4986)
			(layers "F.Cu" "F.Mask" "F.Paste")
			(net "GND")
		)
		(pad "36" smd rect
			(at -2.050034 -33.57499 270)
			(size 0.519938 1.4986)
			(layers "F.Cu" "F.Mask" "F.Paste")
			(net "M_A_CPU0_SA_DQ<20>")
		)
		(pad "37" smd rect
			(at -2.050034 -32.725106 270)
			(size 0.519938 1.4986)
			(layers "F.Cu" "F.Mask" "F.Paste")
			(net "GND")
		)
		(pad "38" smd rect
			(at -2.050034 -31.874968 270)
			(size 0.519938 1.4986)
			(layers "F.Cu" "F.Mask" "F.Paste")
			(net "M_A_CPU0_SA_DQ<21>")
		)
		(pad "39" smd rect
			(at -2.050034 -31.025084 270)
			(size 0.519938 1.4986)
			(layers "F.Cu" "F.Mask" "F.Paste")
			(net "GND")
		)
		(pad "40" smd rect
			(at -2.050034 -30.174946 270)
			(size 0.519938 1.4986)
			(layers "F.Cu" "F.Mask" "F.Paste")
			(net "M_A_CPU0_SA_DQ<24>")
		)
		(pad "41" smd rect
			(at -2.050034 -29.325062 270)
			(size 0.519938 1.4986)
			(layers "F.Cu" "F.Mask" "F.Paste")
			(net "GND")
		)
		(pad "42" smd rect
			(at -2.050034 -28.474924 270)
			(size 0.519938 1.4986)
			(layers "F.Cu" "F.Mask" "F.Paste")
			(net "M_A_CPU0_SA_DQ<25>")
		)
		(pad "43" smd rect
			(at -2.050034 -27.62504 270)
			(size 0.519938 1.4986)
			(layers "F.Cu" "F.Mask" "F.Paste")
			(net "GND")
		)
		(pad "44" smd rect
			(at -2.050034 -26.774902 270)
			(size 0.519938 1.4986)
			(layers "F.Cu" "F.Mask" "F.Paste")
			(net "M_A_CPU0_SA_DQS_DP<3>")
		)
		(pad "45" smd rect
			(at -2.050034 -25.925018 270)
			(size 0.519938 1.4986)
			(layers "F.Cu" "F.Mask" "F.Paste")
			(net "M_A_CPU0_SA_DQS_DN<3>")
		)
	)
)
